# S9S_MB_2U (Grand Teton) — schematic netlist excerpt (pin names and nets, part order shuffled) for the footprints in the layout excerpt that follows; sources: Cadence DE-HDL packaged netlist, KiCad conversion of 03242023_DA0F0TMBIJ0_F0T_Motherboard_J_brd_V01_OCP.brd

R2213  Q_RES  2.2K 5% EMPTY  pkg 0402LF  page 241 : A = SMB_S3M_CPU_3V3AUX_SDA ; B = P3V3_AUX
R841  Q_RES  1K 1% CHIP  pkg 0402LF  page 129 : A = PVCCD_HV_CPU0 ; B = RST_M_CD_CPU0_FPGA_N

(kicad_pcb
	(version 20260206)
	(generator "pcbnew")
	(generator_version "10.0")
	(general
		(thickness 1.6)
		(legacy_teardrops no)
	)
	(paper "A4")
	(title_block
		(title "03242023_DA0F0TMBIJ0_F0T_Motherboard_J_brd_V01_OCP.brd")
		(comment 1 "Grand Teton / footprints 5996-5997 of 6105")
	)
	(layers
		(0 "F.Cu" signal "TOP")
		(4 "In1.Cu" signal "GND")
		(6 "In2.Cu" signal "IN1")
		(8 "In3.Cu" signal "GND1")
		(10 "In4.Cu" signal "IN2")
		(12 "In5.Cu" signal "GND2")
		(14 "In6.Cu" signal "IN3")
		(16 "In7.Cu" signal "GND3")
		(18 "In8.Cu" signal "VCC")
		(20 "In9.Cu" signal "VCC1")
		(22 "In10.Cu" signal "GND4")
		(24 "In11.Cu" signal "IN4")
		(26 "In12.Cu" signal "GND5")
		(28 "In13.Cu" signal "IN5")
		(30 "In14.Cu" signal "GND6")
		(32 "In15.Cu" signal "IN6")
		(34 "In16.Cu" signal "GND7")
		(2 "B.Cu" signal "BOTTOM")
		(9 "F.Adhes" user "F.Adhesive")
		(11 "B.Adhes" user "B.Adhesive")
		(13 "F.Paste" user "Package Geometry/Pastemask Top")
		(15 "B.Paste" user "Package Geometry/Pastemask Bottom")
		(5 "F.SilkS" user "Ref Des/Silkscreen Top")
		(7 "B.SilkS" user "Ref Des/Silkscreen Bottom")
		(1 "F.Mask" user "Board Geometry/Soldermask Top")
		(3 "B.Mask" user "Board Geometry/Soldermask Bottom")
		(17 "Dwgs.User" user "User.Drawings")
		(19 "Cmts.User" user "User.Comments")
		(21 "Eco1.User" user "User.Eco1")
		(23 "Eco2.User" user "User.Eco2")
		(25 "Edge.Cuts" user "Board Geometry/Outline")
		(27 "Margin" user)
		(31 "F.CrtYd" user "Package Geometry/Place Bound Top")
		(29 "B.CrtYd" user "Package Geometry/Place Bound Bottom")
		(35 "F.Fab" user "Ref Des/Assembly Top")
		(33 "B.Fab" user "Ref Des/Assembly Bottom")
	)
	(footprint ""
		(layer "B.Cu")
		(at 150.42388 -22.824948 -90)
		(property "Reference" "R2213"
			(at 0 0 90)
			(layer "B.SilkS")
			(hide yes)
			(effects
				(font
					(size 1.27 1.27)
				)
				(justify mirror)
			)
		)
		(property "Value" ""
			(at 0 0 90)
			(layer "B.Fab")
			(effects
				(font
					(size 1.27 1.27)
				)
				(justify mirror)
			)
		)
		(duplicate_pad_numbers_are_jumpers no)
		(fp_line
			(start -0.7874 0.4064)
			(end 0.7874 0.4064)
			(stroke
				(width 0.1524)
				(type default)
			)
			(layer "B.SilkS")
		)
		(fp_line
			(start 0.7874 0.4064)
			(end 0.7874 -0.4064)
			(stroke
				(width 0.1524)
				(type default)
			)
			(layer "B.SilkS")
		)
		(fp_line
			(start -0.7874 -0.4064)
			(end -0.7874 0.4064)
			(stroke
				(width 0.1524)
				(type default)
			)
			(layer "B.SilkS")
		)
		(fp_line
			(start 0.7874 -0.4064)
			(end -0.7874 -0.4064)
			(stroke
				(width 0.1524)
				(type default)
			)
			(layer "B.SilkS")
		)
		(fp_line
			(start -0.67945 0.3048)
			(end -0.120396 0.3048)
			(stroke
				(width 0.1)
				(type default)
			)
			(layer "B.Fab")
		)
		(fp_line
			(start -0.120396 0.3048)
			(end -0.120396 0.2794)
			(stroke
				(width 0.1)
				(type default)
			)
			(layer "B.Fab")
		)
		(fp_line
			(start 0.12065 0.3048)
			(end 0.67945 0.3048)
			(stroke
				(width 0.1)
				(type default)
			)
			(layer "B.Fab")
		)
		(fp_line
			(start 0.67945 0.3048)
			(end 0.67945 -0.305054)
			(stroke
				(width 0.1)
				(type default)
			)
			(layer "B.Fab")
		)
		(fp_line
			(start -0.120396 0.2794)
			(end 0.12065 0.2794)
			(stroke
				(width 0.1)
				(type default)
			)
			(layer "B.Fab")
		)
		(fp_line
			(start 0.12065 0.2794)
			(end 0.12065 0.3048)
			(stroke
				(width 0.1)
				(type default)
			)
			(layer "B.Fab")
		)
		(fp_line
			(start -0.12065 -0.2794)
			(end -0.12065 -0.3048)
			(stroke
				(width 0.1)
				(type default)
			)
			(layer "B.Fab")
		)
		(fp_line
			(start 0.12065 -0.2794)
			(end -0.12065 -0.2794)
			(stroke
				(width 0.1)
				(type default)
			)
			(layer "B.Fab")
		)
		(fp_line
			(start -0.67945 -0.3048)
			(end -0.67945 0.3048)
			(stroke
				(width 0.1)
				(type default)
			)
			(layer "B.Fab")
		)
		(fp_line
			(start -0.12065 -0.3048)
			(end -0.67945 -0.3048)
			(stroke
				(width 0.1)
				(type default)
			)
			(layer "B.Fab")
		)
		(fp_line
			(start 0.12065 -0.305054)
			(end 0.12065 -0.2794)
			(stroke
				(width 0.1)
				(type default)
			)
			(layer "B.Fab")
		)
		(fp_line
			(start 0.67945 -0.305054)
			(end 0.12065 -0.305054)
			(stroke
				(width 0.1)
				(type default)
			)
			(layer "B.Fab")
		)
		(pad "1" smd circle
			(at 0.40005 0 90)
			(size 0 0)
			(layers "B.Cu" "B.Mask" "B.Paste")
			(net "SMB_S3M_CPU_3V3AUX_SDA")
		)
		(pad "2" smd circle
			(at -0.40005 0 90)
			(size 0 0)
			(layers "B.Cu" "B.Mask" "B.Paste")
			(net "P3V3_AUX")
		)
	)
	(footprint ""
		(layer "B.Cu")
		(at 270.700246 -193.503296 -90)
		(property "Reference" "R841"
			(at 0 0 90)
			(layer "B.SilkS")
			(hide yes)
			(effects
				(font
					(size 1.27 1.27)
				)
				(justify mirror)
			)
		)
		(property "Value" ""
			(at 0 0 90)
			(layer "B.Fab")
			(effects
				(font
					(size 1.27 1.27)
				)
				(justify mirror)
			)
		)
		(duplicate_pad_numbers_are_jumpers no)
		(fp_line
			(start -0.7874 0.4064)
			(end 0.7874 0.4064)
			(stroke
				(width 0.1524)
				(type default)
			)
			(layer "B.SilkS")
		)
		(fp_line
			(start 0.7874 0.4064)
			(end 0.7874 -0.4064)
			(stroke
				(width 0.1524)
				(type default)
			)
			(layer "B.SilkS")
		)
		(fp_line
			(start -0.7874 -0.4064)
			(end -0.7874 0.4064)
			(stroke
				(width 0.1524)
				(type default)
			)
			(layer "B.SilkS")
		)
		(fp_line
			(start 0.7874 -0.4064)
			(end -0.7874 -0.4064)
			(stroke
				(width 0.1524)
				(type default)
			)
			(layer "B.SilkS")
		)
		(fp_line
			(start -0.67945 0.3048)
			(end -0.120396 0.3048)
			(stroke
				(width 0.1)
				(type default)
			)
			(layer "B.Fab")
		)
		(fp_line
			(start -0.120396 0.3048)
			(end -0.120396 0.2794)
			(stroke
				(width 0.1)
				(type default)
			)
			(layer "B.Fab")
		)
		(fp_line
			(start 0.12065 0.3048)
			(end 0.67945 0.3048)
			(stroke
				(width 0.1)
				(type default)
			)
			(layer "B.Fab")
		)
		(fp_line
			(start 0.67945 0.3048)
			(end 0.67945 -0.305054)
			(stroke
				(width 0.1)
				(type default)
			)
			(layer "B.Fab")
		)
		(fp_line
			(start -0.120396 0.2794)
			(end 0.12065 0.2794)
			(stroke
				(width 0.1)
				(type default)
			)
			(layer "B.Fab")
		)
		(fp_line
			(start 0.12065 0.2794)
			(end 0.12065 0.3048)
			(stroke
				(width 0.1)
				(type default)
			)
			(layer "B.Fab")
		)
		(fp_line
			(start -0.12065 -0.2794)
			(end -0.12065 -0.3048)
			(stroke
				(width 0.1)
				(type default)
			)
			(layer "B.Fab")
		)
		(fp_line
			(start 0.12065 -0.2794)
			(end -0.12065 -0.2794)
			(stroke
				(width 0.1)
				(type default)
			)
			(layer "B.Fab")
		)
		(fp_line
			(start -0.67945 -0.3048)
			(end -0.67945 0.3048)
			(stroke
				(width 0.1)
				(type default)
			)
			(layer "B.Fab")
		)
		(fp_line
			(start -0.12065 -0.3048)
			(end -0.67945 -0.3048)
			(stroke
				(width 0.1)
				(type default)
			)
			(layer "B.Fab")
		)
		(fp_line
			(start 0.12065 -0.305054)
			(end 0.12065 -0.2794)
			(stroke
				(width 0.1)
				(type default)
			)
			(layer "B.Fab")
		)
		(fp_line
			(start 0.67945 -0.305054)
			(end 0.12065 -0.305054)
			(stroke
				(width 0.1)
				(type default)
			)
			(layer "B.Fab")
		)
		(pad "1" smd circle
			(at 0.40005 0 90)
			(size 0 0)
			(layers "B.Cu" "B.Mask" "B.Paste")
			(net "PVCCD_HV_CPU0")
		)
		(pad "2" smd circle
			(at -0.40005 0 90)
			(size 0 0)
			(layers "B.Cu" "B.Mask" "B.Paste")
			(net "RST_M_CD_CPU0_FPGA_N")
		)
	)
)
